(kicad_pcb
	(version 20260206)
	(generator "pcbnew")
	(generator_version "10.0")
	(general
		(thickness 1.6)
		(legacy_teardrops no)
	)
	(paper "A4")
	(title_block
		(title "v2-pdb — ms_pdb_v2.brd")
		(comment 1 "Open CloudServer (Microsoft) / footprints 173-180 of 348")
	)
	(layers
		(0 "F.Cu" signal "TOP")
		(4 "In1.Cu" signal "GND")
		(6 "In2.Cu" signal "IN1")
		(8 "In3.Cu" signal "VCC")
		(10 "In4.Cu" signal "VCC1")
		(12 "In5.Cu" signal "IN2")
		(14 "In6.Cu" signal "GND1")
		(2 "B.Cu" signal "BOTTOM")
		(9 "F.Adhes" user "F.Adhesive")
		(11 "B.Adhes" user "B.Adhesive")
		(13 "F.Paste" user "Package Geometry/Pastemask Top")
		(15 "B.Paste" user "Package Geometry/Pastemask Bottom")
		(5 "F.SilkS" user "Ref Des/Silkscreen Top")
		(7 "B.SilkS" user "Ref Des/Silkscreen Bottom")
		(1 "F.Mask" user "Board Geometry/Soldermask Top")
		(3 "B.Mask" user "Board Geometry/Soldermask Bottom")
		(17 "Dwgs.User" user "User.Drawings")
		(19 "Cmts.User" user "User.Comments")
		(21 "Eco1.User" user "User.Eco1")
		(23 "Eco2.User" user "User.Eco2")
		(25 "Edge.Cuts" user "Board Geometry/Outline")
		(27 "Margin" user)
		(31 "F.CrtYd" user "Package Geometry/Place Bound Top")
		(29 "B.CrtYd" user "Package Geometry/Place Bound Bottom")
		(35 "F.Fab" user "Ref Des/Assembly Top")
		(33 "B.Fab" user "Ref Des/Assembly Bottom")
	)
	(footprint ""
		(layer "F.Cu")
		(at 71.044562 -439.03646 90)
		(property "Reference" "C76"
			(at 1.345946 0.134112 90)
			(unlocked yes)
			(layer "F.SilkS")
			(effects
				(font
					(size 0.7874 0.5842)
					(thickness 0.1524)
				)
				(justify left)
			)
		)
		(property "Value" ""
			(at 0 0 90)
			(layer "F.Fab")
			(effects
				(font
					(size 1.27 1.27)
				)
			)
		)
		(duplicate_pad_numbers_are_jumpers no)
		(fp_line
			(start 0.7874 -0.4064)
			(end 0.7874 0.4064)
			(stroke
				(width 0.1524)
				(type default)
			)
			(layer "F.SilkS")
		)
		(fp_line
			(start -0.7874 -0.4064)
			(end 0.7874 -0.4064)
			(stroke
				(width 0.1524)
				(type default)
			)
			(layer "F.SilkS")
		)
		(fp_line
			(start 0 0.381)
			(end 0 -0.381)
			(stroke
				(width 0.1524)
				(type default)
			)
			(layer "F.SilkS")
		)
		(fp_line
			(start 0.7874 0.4064)
			(end -0.7874 0.4064)
			(stroke
				(width 0.1524)
				(type default)
			)
			(layer "F.SilkS")
		)
		(fp_line
			(start -0.7874 0.4064)
			(end -0.7874 -0.4064)
			(stroke
				(width 0.1524)
				(type default)
			)
			(layer "F.SilkS")
		)
		(fp_poly
			(pts
				(xy -0.5334 0.254) (xy -0.635 0.254) (xy -0.635 0.2286) (xy -0.635 -0.254) (xy -0.5334 -0.254) (xy -0.5334 -0.2794)
				(xy 0.5334 -0.2794) (xy 0.5334 -0.254) (xy 0.635 -0.254) (xy 0.635 0.254) (xy 0.5334 0.254) (xy 0.5334 0.2794)
				(xy -0.508 0.2794) (xy -0.5334 0.2794)
			)
			(stroke
				(width 0)
				(type default)
			)
			(fill no)
			(layer "F.CrtYd")
		)
		(pad "1" smd rect
			(at 0.40005 0 90)
			(size 0.4572 0.508)
			(layers "F.Cu" "F.Mask" "F.Paste")
			(net "P12V")
		)
		(pad "2" smd rect
			(at -0.40005 0 90)
			(size 0.4572 0.508)
			(layers "F.Cu" "F.Mask" "F.Paste")
			(net "GND")
		)
	)
	(footprint ""
		(layer "F.Cu")
		(at 39.798752 -197.274942)
		(property "Reference" "R42"
			(at 2.029968 0.33401 0)
			(unlocked yes)
			(layer "F.SilkS")
			(effects
				(font
					(size 0.7874 0.5842)
					(thickness 0.1524)
				)
				(justify left)
			)
		)
		(property "Value" ""
			(at 0 0 0)
			(layer "F.Fab")
			(effects
				(font
					(size 1.27 1.27)
				)
			)
		)
		(duplicate_pad_numbers_are_jumpers no)
		(fp_line
			(start -0.7874 -0.4064)
			(end 0.7874 -0.4064)
			(stroke
				(width 0.1524)
				(type default)
			)
			(layer "F.SilkS")
		)
		(fp_line
			(start -0.7874 0.4064)
			(end -0.7874 -0.4064)
			(stroke
				(width 0.1524)
				(type default)
			)
			(layer "F.SilkS")
		)
		(fp_line
			(start 0.7874 -0.4064)
			(end 0.7874 0.4064)
			(stroke
				(width 0.1524)
				(type default)
			)
			(layer "F.SilkS")
		)
		(fp_line
			(start 0.7874 0.4064)
			(end -0.7874 0.4064)
			(stroke
				(width 0.1524)
				(type default)
			)
			(layer "F.SilkS")
		)
		(fp_poly
			(pts
				(xy -0.508 0.2794) (xy -0.508 0.2286) (xy -0.635 0.2286) (xy -0.635 -0.254) (xy -0.5334 -0.254)
				(xy -0.5334 -0.2794) (xy 0.5334 -0.2794) (xy 0.5334 -0.254) (xy 0.635 -0.254) (xy 0.635 0.254) (xy 0.5334 0.254)
				(xy 0.5334 0.2794)
			)
			(stroke
				(width 0)
				(type default)
			)
			(fill no)
			(layer "F.CrtYd")
		)
		(pad "1" smd rect
			(at 0.40005 0)
			(size 0.4572 0.508)
			(layers "F.Cu" "F.Mask" "F.Paste")
			(net "GND")
		)
		(pad "2" smd rect
			(at -0.40005 0)
			(size 0.4572 0.508)
			(layers "F.Cu" "F.Mask" "F.Paste")
			(net "P12V_STBY")
		)
	)
	(footprint ""
		(layer "F.Cu")
		(at 91.399868 -108.909866)
		(property "Reference" "H17"
			(at -5.1308 -5.23113 0)
			(unlocked yes)
			(layer "F.SilkS")
			(effects
				(font
					(size 0.7874 0.5842)
					(thickness 0.1524)
				)
				(justify left)
			)
		)
		(property "Value" ""
			(at 0 0 0)
			(layer "F.Fab")
			(effects
				(font
					(size 1.27 1.27)
				)
			)
		)
		(duplicate_pad_numbers_are_jumpers no)
		(fp_circle
			(center 0 0)
			(end 4.826 0)
			(stroke
				(width 0.1524)
				(type default)
			)
			(fill no)
			(layer "F.SilkS")
		)
		(fp_circle
			(center 0 0)
			(end 4.826 0)
			(stroke
				(width 0.1524)
				(type default)
			)
			(fill no)
			(layer "B.SilkS")
		)
		(fp_poly
			(pts
				(arc
					(start 0 4.0132)
					(mid 0 -4.0132)
					(end 0 4.0132)
				)
			)
			(stroke
				(width 0)
				(type default)
			)
			(fill no)
			(layer "F.CrtYd")
		)
		(pad "" np_thru_hole circle
			(at 0 0)
			(size 8.001 8.001)
			(drill 8.001)
			(layers "*.Cu" "*.Mask")
			(clearance 0.381)
			(thermal_gap 0.381)
		)
		(zone
			(layers "F.Cu" "B.Cu" "In1.Cu" "In2.Cu" "In3.Cu" "In4.Cu" "In5.Cu" "In6.Cu")
			(hatch none 0.5)
			(connect_pads
				(clearance 0)
			)
			(min_thickness 0.25)
			(keepout
				(tracks not_allowed)
				(vias allowed)
				(pads allowed)
				(copperpour not_allowed)
				(footprints allowed)
			)
			(placement
				(enabled no)
				(sheetname "")
			)
			(fill
				(thermal_gap 0.5)
				(thermal_bridge_width 0.5)
				(island_removal_mode 0)
			)
			(polygon
				(pts
					(arc
						(start 91.399868 -104.388666)
						(mid 91.399868 -113.431066)
						(end 91.399868 -104.388666)
					)
				)
			)
		)
	)
	(footprint ""
		(layer "F.Cu")
		(at 26.102056 -272.345404)
		(property "Reference" "R57"
			(at -4.037838 -0.005334 0)
			(unlocked yes)
			(layer "F.SilkS")
			(effects
				(font
					(size 0.7874 0.5842)
					(thickness 0.1524)
				)
				(justify left)
			)
		)
		(property "Value" ""
			(at 0 0 0)
			(layer "F.Fab")
			(effects
				(font
					(size 1.27 1.27)
				)
			)
		)
		(duplicate_pad_numbers_are_jumpers no)
		(fp_line
			(start -0.7874 -0.4064)
			(end 0.7874 -0.4064)
			(stroke
				(width 0.1524)
				(type default)
			)
			(layer "F.SilkS")
		)
		(fp_line
			(start -0.7874 0.4064)
			(end -0.7874 -0.4064)
			(stroke
				(width 0.1524)
				(type default)
			)
			(layer "F.SilkS")
		)
		(fp_line
			(start 0.7874 -0.4064)
			(end 0.7874 0.4064)
			(stroke
				(width 0.1524)
				(type default)
			)
			(layer "F.SilkS")
		)
		(fp_line
			(start 0.7874 0.4064)
			(end -0.7874 0.4064)
			(stroke
				(width 0.1524)
				(type default)
			)
			(layer "F.SilkS")
		)
		(fp_poly
			(pts
				(xy -0.508 0.2794) (xy -0.508 0.2286) (xy -0.635 0.2286) (xy -0.635 -0.254) (xy -0.5334 -0.254)
				(xy -0.5334 -0.2794) (xy 0.5334 -0.2794) (xy 0.5334 -0.254) (xy 0.635 -0.254) (xy 0.635 0.254) (xy 0.5334 0.254)
				(xy 0.5334 0.2794)
			)
			(stroke
				(width 0)
				(type default)
			)
			(fill no)
			(layer "F.CrtYd")
		)
		(pad "1" smd rect
			(at 0.40005 0)
			(size 0.4572 0.508)
			(layers "F.Cu" "F.Mask" "F.Paste")
			(net "PSU4_RESET")
		)
		(pad "2" smd rect
			(at -0.40005 0)
			(size 0.4572 0.508)
			(layers "F.Cu" "F.Mask" "F.Paste")
			(net "GND")
		)
	)
	(footprint ""
		(layer "F.Cu")
		(at 16.599916 -295.89984)
		(property "Reference" "H4"
			(at -1.466596 -9.400032 0)
			(unlocked yes)
			(layer "F.SilkS")
			(effects
				(font
					(size 0.7874 0.5842)
					(thickness 0.1524)
				)
				(justify left)
			)
		)
		(property "Value" ""
			(at 0 0 0)
			(layer "F.Fab")
			(effects
				(font
					(size 1.27 1.27)
				)
			)
		)
		(duplicate_pad_numbers_are_jumpers no)
		(fp_circle
			(center 0 0)
			(end 7.999984 0)
			(stroke
				(width 0.1524)
				(type default)
			)
			(fill no)
			(layer "F.SilkS")
		)
		(fp_circle
			(center 0 0)
			(end 14.7066 0)
			(stroke
				(width 0.1524)
				(type default)
			)
			(fill no)
			(layer "B.SilkS")
		)
		(fp_poly
			(pts
				(arc
					(start 0 5.0038)
					(mid 0 -5.0038)
					(end 0 5.0038)
				)
			)
			(stroke
				(width 0)
				(type default)
			)
			(fill no)
			(layer "F.CrtYd")
		)
		(pad "" np_thru_hole circle
			(at 0 0)
			(size 4.0132 4.0132)
			(drill 4.0132)
			(layers "*.Cu" "*.Mask")
			(clearance 0.381)
			(thermal_gap 0.381)
		)
		(pad "2" thru_hole circle
			(at 0 -3.50012)
			(size 0.762 0.762)
			(drill 0.5588)
			(layers "*.Cu" "*.Mask")
			(remove_unused_layers no)
			(net "GND")
			(clearance 0.1524)
			(thermal_gap 0.1524)
		)
		(pad "3" thru_hole circle
			(at -2.500122 -2.500122)
			(size 0.762 0.762)
			(drill 0.5588)
			(layers "*.Cu" "*.Mask")
			(remove_unused_layers no)
			(net "GND")
			(clearance 0.1524)
			(thermal_gap 0.1524)
		)
		(pad "4" thru_hole circle
			(at -3.50012 0)
			(size 0.762 0.762)
			(drill 0.5588)
			(layers "*.Cu" "*.Mask")
			(remove_unused_layers no)
			(net "GND")
			(clearance 0.1524)
			(thermal_gap 0.1524)
		)
		(pad "5" thru_hole circle
			(at -2.500122 2.500122)
			(size 0.762 0.762)
			(drill 0.5588)
			(layers "*.Cu" "*.Mask")
			(remove_unused_layers no)
			(net "GND")
			(clearance 0.1524)
			(thermal_gap 0.1524)
		)
		(pad "6" thru_hole circle
			(at 0 3.50012)
			(size 0.762 0.762)
			(drill 0.5588)
			(layers "*.Cu" "*.Mask")
			(remove_unused_layers no)
			(net "GND")
			(clearance 0.1524)
			(thermal_gap 0.1524)
		)
		(pad "7" thru_hole circle
			(at 2.500122 2.500122)
			(size 0.762 0.762)
			(drill 0.5588)
			(layers "*.Cu" "*.Mask")
			(remove_unused_layers no)
			(net "GND")
			(clearance 0.1524)
			(thermal_gap 0.1524)
		)
		(pad "8" thru_hole circle
			(at 3.50012 0)
			(size 0.762 0.762)
			(drill 0.5588)
			(layers "*.Cu" "*.Mask")
			(remove_unused_layers no)
			(net "GND")
			(clearance 0.1524)
			(thermal_gap 0.1524)
		)
		(pad "9" thru_hole circle
			(at 2.500122 -2.500122)
			(size 0.762 0.762)
			(drill 0.5588)
			(layers "*.Cu" "*.Mask")
			(remove_unused_layers no)
			(net "GND")
			(clearance 0.1524)
			(thermal_gap 0.1524)
		)
		(zone
			(layer "F.Cu")
			(hatch none 0.5)
			(connect_pads
				(clearance 0)
			)
			(min_thickness 0.25)
			(keepout
				(tracks not_allowed)
				(vias allowed)
				(pads allowed)
				(copperpour not_allowed)
				(footprints allowed)
			)
			(placement
				(enabled no)
				(sheetname "")
			)
			(fill
				(thermal_gap 0.5)
				(thermal_bridge_width 0.5)
				(island_removal_mode 0)
			)
			(polygon
				(pts
					(arc
						(start 16.599916 -303.90084)
						(mid 8.598916 -295.89984)
						(end 16.599916 -287.89884)
					)
					(arc
						(start 16.599916 -287.89884)
						(mid 18.035016 -289.33394)
						(end 16.599916 -290.76904)
					)
					(arc
						(start 16.599916 -290.76904)
						(mid 11.469116 -295.89984)
						(end 16.599916 -301.03064)
					)
					(arc
						(start 16.599916 -301.03064)
						(mid 18.035016 -302.46574)
						(end 16.599916 -303.90084)
					)
				)
			)
		)
		(zone
			(layer "F.Cu")
			(hatch none 0.5)
			(connect_pads
				(clearance 0)
			)
			(min_thickness 0.25)
			(keepout
				(tracks not_allowed)
				(vias allowed)
				(pads allowed)
				(copperpour not_allowed)
				(footprints allowed)
			)
			(placement
				(enabled no)
				(sheetname "")
			)
			(fill
				(thermal_gap 0.5)
				(thermal_bridge_width 0.5)
				(island_removal_mode 0)
			)
			(polygon
				(pts
					(arc
						(start 16.599916 -303.90084)
						(mid 24.600916 -295.89984)
						(end 16.599916 -287.89884)
					)
					(arc
						(start 16.599916 -287.89884)
						(mid 15.164816 -289.33394)
						(end 16.599916 -290.76904)
					)
					(arc
						(start 16.599916 -290.76904)
						(mid 21.730716 -295.89984)
						(end 16.599916 -301.03064)
					)
					(arc
						(start 16.599916 -301.03064)
						(mid 15.164816 -302.46574)
						(end 16.599916 -303.90084)
					)
				)
			)
		)
		(zone
			(layers "F.Cu" "B.Cu" "In1.Cu" "In2.Cu" "In3.Cu" "In4.Cu" "In5.Cu" "In6.Cu")
			(hatch none 0.5)
			(connect_pads
				(clearance 0)
			)
			(min_thickness 0.25)
			(keepout
				(tracks not_allowed)
				(vias allowed)
				(pads allowed)
				(copperpour not_allowed)
				(footprints allowed)
			)
			(placement
				(enabled no)
				(sheetname "")
			)
			(fill
				(thermal_gap 0.5)
				(thermal_bridge_width 0.5)
				(island_removal_mode 0)
			)
			(polygon
				(pts
					(arc
						(start 16.599916 -293.38778)
						(mid 16.599916 -298.4119)
						(end 16.599916 -293.38778)
					)
				)
			)
		)
	)
	(footprint ""
		(layer "F.Cu")
		(at 16.263366 -449.79209)
		(property "Reference" "C87"
			(at -1.023366 5.60705 0)
			(unlocked yes)
			(layer "F.SilkS")
			(effects
				(font
					(size 0.7874 0.5842)
					(thickness 0.1524)
				)
				(justify left)
			)
		)
		(property "Value" ""
			(at 0 0 0)
			(layer "F.Fab")
			(effects
				(font
					(size 1.27 1.27)
				)
			)
		)
		(duplicate_pad_numbers_are_jumpers no)
		(fp_line
			(start -1.905 -0.8636)
			(end 1.905 -0.8636)
			(stroke
				(width 0.1524)
				(type default)
			)
			(layer "F.SilkS")
		)
		(fp_line
			(start -1.905 0.8636)
			(end -1.905 -0.8636)
			(stroke
				(width 0.1524)
				(type default)
			)
			(layer "F.SilkS")
		)
		(fp_line
			(start 0 0.8382)
			(end 0 -0.8382)
			(stroke
				(width 0.1524)
				(type default)
			)
			(layer "F.SilkS")
		)
		(fp_line
			(start 1.905 -0.8636)
			(end 1.905 0.8636)
			(stroke
				(width 0.1524)
				(type default)
			)
			(layer "F.SilkS")
		)
		(fp_line
			(start 1.905 0.8636)
			(end -1.905 0.8636)
			(stroke
				(width 0.1524)
				(type default)
			)
			(layer "F.SilkS")
		)
		(fp_rect
			(start -1.524 0.7366)
			(end 1.524 -0.7366)
			(stroke
				(width 0)
				(type default)
			)
			(fill no)
			(layer "F.CrtYd")
		)
		(pad "1" smd rect
			(at 0.94996 0)
			(size 1.1176 1.3716)
			(layers "F.Cu" "F.Mask" "F.Paste")
			(net "P12V")
		)
		(pad "2" smd rect
			(at -0.94996 0)
			(size 1.1176 1.3716)
			(layers "F.Cu" "F.Mask" "F.Paste")
			(net "GND")
		)
	)
	(footprint ""
		(layer "F.Cu")
		(at 3.414014 -127.08636 -90)
		(property "Reference" "R150"
			(at 2.120392 1.17729 90)
			(unlocked yes)
			(layer "F.SilkS")
			(effects
				(font
					(size 0.7874 0.5842)
					(thickness 0.1524)
				)
				(justify left)
			)
		)
		(property "Value" ""
			(at 0 0 270)
			(layer "F.Fab")
			(effects
				(font
					(size 1.27 1.27)
				)
			)
		)
		(duplicate_pad_numbers_are_jumpers no)
		(fp_line
			(start -0.7874 0.4064)
			(end -0.7874 -0.4064)
			(stroke
				(width 0.1524)
				(type default)
			)
			(layer "F.SilkS")
		)
		(fp_line
			(start 0.7874 0.4064)
			(end -0.7874 0.4064)
			(stroke
				(width 0.1524)
				(type default)
			)
			(layer "F.SilkS")
		)
		(fp_line
			(start -0.7874 -0.4064)
			(end 0.7874 -0.4064)
			(stroke
				(width 0.1524)
				(type default)
			)
			(layer "F.SilkS")
		)
		(fp_line
			(start 0.7874 -0.4064)
			(end 0.7874 0.4064)
			(stroke
				(width 0.1524)
				(type default)
			)
			(layer "F.SilkS")
		)
		(fp_poly
			(pts
				(xy -0.508 0.2794) (xy -0.508 0.2286) (xy -0.635 0.2286) (xy -0.635 -0.254) (xy -0.5334 -0.254)
				(xy -0.5334 -0.2794) (xy 0.5334 -0.2794) (xy 0.5334 -0.254) (xy 0.635 -0.254) (xy 0.635 0.254) (xy 0.5334 0.254)
				(xy 0.5334 0.2794)
			)
			(stroke
				(width 0)
				(type default)
			)
			(fill no)
			(layer "F.CrtYd")
		)
		(pad "1" smd rect
			(at 0.40005 0 270)
			(size 0.4572 0.508)
			(layers "F.Cu" "F.Mask" "F.Paste")
			(net "GND")
		)
		(pad "2" smd rect
			(at -0.40005 0 270)
			(size 0.4572 0.508)
			(layers "F.Cu" "F.Mask" "F.Paste")
			(net "N42130542")
		)
	)
	(footprint ""
		(layer "F.Cu")
		(at 19.780504 -454.899522)
		(property "Reference" "U2"
			(at -4.064 -3.52933 0)
			(unlocked yes)
			(layer "F.SilkS")
			(effects
				(font
					(size 0.7874 0.5842)
					(thickness 0.1524)
				)
				(justify left)
			)
		)
		(property "Value" ""
			(at 0 0 0)
			(layer "F.Fab")
			(effects
				(font
					(size 1.27 1.27)
				)
			)
		)
		(duplicate_pad_numbers_are_jumpers no)
		(fp_line
			(start -2.5146 -1.4224)
			(end 2.5146 -1.4224)
			(stroke
				(width 0.1524)
				(type default)
			)
			(layer "F.SilkS")
		)
		(fp_line
			(start -2.5146 -0.4572)
			(end -2.5146 -1.4224)
			(stroke
				(width 0.1524)
				(type default)
			)
			(layer "F.SilkS")
		)
		(fp_line
			(start -2.5146 0.4572)
			(end -2.0574 0)
			(stroke
				(width 0.1524)
				(type default)
			)
			(layer "F.SilkS")
		)
		(fp_line
			(start -2.5146 1.4224)
			(end -2.5146 0.4572)
			(stroke
				(width 0.1524)
				(type default)
			)
			(layer "F.SilkS")
		)
		(fp_line
			(start -2.0574 0)
			(end -2.5146 -0.4572)
			(stroke
				(width 0.1524)
				(type default)
			)
			(layer "F.SilkS")
		)
		(fp_line
			(start 2.5146 -1.4224)
			(end 2.5146 1.4224)
			(stroke
				(width 0.1524)
				(type default)
			)
			(layer "F.SilkS")
		)
		(fp_line
			(start 2.5146 1.4224)
			(end -2.5146 1.4224)
			(stroke
				(width 0.1524)
				(type default)
			)
			(layer "F.SilkS")
		)
		(fp_circle
			(center -1.905 0.889)
			(end -1.651 0.889)
			(stroke
				(width 0.1524)
				(type default)
			)
			(fill no)
			(layer "F.SilkS")
		)
		(fp_poly
			(pts
				(xy -2.1844 3.5052) (xy -2.1844 2.0066) (xy -2.5146 2.0066) (xy -2.5146 -2.0066) (xy -2.1844 -2.0066)
				(xy -2.1844 -3.5052) (xy 2.1844 -3.5052) (xy 2.1844 -2.0066) (xy 2.5146 -2.0066) (xy 2.5146 2.0066)
				(xy 2.1844 2.0066) (xy 2.1844 3.5052)
			)
			(stroke
				(width 0)
				(type default)
			)
			(fill no)
			(layer "F.CrtYd")
		)
		(pad "1" smd rect
			(at -1.905 2.6416)
			(size 0.5588 1.7272)
			(layers "F.Cu" "F.Mask" "F.Paste")
			(net "N42241895")
		)
		(pad "2" smd rect
			(at -0.635 2.6416)
			(size 0.5588 1.7272)
			(layers "F.Cu" "F.Mask" "F.Paste")
			(net "P12V")
		)
		(pad "3" smd rect
			(at 0.635 2.6416)
			(size 0.5588 1.7272)
			(layers "F.Cu" "F.Mask" "F.Paste")
			(net "P3V3_BUF")
		)
		(pad "4" smd rect
			(at 1.905 2.6416)
			(size 0.5588 1.7272)
			(layers "F.Cu" "F.Mask" "F.Paste")
			(net "N42242090")
		)
		(pad "5" smd rect
			(at 1.905 -2.6416)
			(size 0.5588 1.7272)
			(layers "F.Cu" "F.Mask" "F.Paste")
			(net "GND")
		)
		(pad "6" smd rect
			(at 0.635 -2.6416)
			(size 0.5588 1.7272)
			(layers "F.Cu" "F.Mask" "F.Paste")
			(net "GND")
		)
		(pad "7" smd rect
			(at -0.635 -2.6416)
			(size 0.5588 1.7272)
			(layers "F.Cu" "F.Mask" "F.Paste")
			(net "GND")
		)
		(pad "8" smd rect
			(at -1.905 -2.6416)
			(size 0.5588 1.7272)
			(layers "F.Cu" "F.Mask" "F.Paste")
			(net "GND")
		)
	)
)
